# BASEBOARD_FAB2 (Tioga Pass) — schematic netlist excerpt (pin names and nets, part order shuffled) for the footprints in the layout excerpt that follows; sources: Cadence DE-HDL packaged netlist, KiCad conversion of Wiwynn_Tioga_Pass_MB.brd

U8D7  LCMXO2_A  IC  pkg 256BGA  page 190
  VCC(0)  = P3V3_STBY
  NC(0)  = NC
  PT11C  = FM_PCH_PRSNT_N
  PT10A  = FM_P3V3_CPLD_EN
  PT11A  = TP_CPLD1_PT11A
  PT12D_TDI  = JTAG_PLD_TDI
  PT16C_TCK  = JTAG_PLD_TCK
  PT17B_PCLKC0_1  = TP_CPLD1_PT17B_PCLKC0_1
  PT18C_SCL_PCLKT0_0  = SMB_SENSOR_STBY_LVC3_SCL
  PT19B  = FM_PVCCIN_PVCCSA_CPU0_EN_LVC1
  PT21A  = FM_CPU0_OR_CPU1_MCP_PRES
  PT22B  = PU_THERMTRIP_FORCE_N
  PT24C_INITN  = TP_CPLD1_PT24C_INITN
  PT22D  = TP_CPLD1_PT22D
  PT24B  = TP_CPLD1_PT24B
  VCC(1)  = P3V3_STBY
  PL1C  = RST_PCIE_PCH_PERST_N
  GND(0)  = GND
  PT9C  = FM_CTNR_PS_ON
  PT11D  = PWRGD_PVTT_CPU0
  PT9B  = PWRGD_P12V_MAIN
  PT11B  = TP_CPLD1_PT11B
  PT13A  = TP_CPLD1_PT13A
  PT16D_TMS  = JTAG_PLD_TMS
  PT19A  = PU_RST_PERST_BIT1
  PT20D_PROGRAMN  = PU_CPLD1_PT20D_PROGRAMN
  PT22A  = PWRGD_DSW_PWROK
  PT23B  = FM_PCH_PWRBTN_R1_N
  PT22C  = TP_CPLD1_PT22C
  PT24A  = FM_SINT_PRSNT_N
  GND(1)  = GND
  PR1D  = FM_ADR_COMPLETE_DLY
  PL2C  = RST_PCIE_CPU_DEV1_N
  PL1D  = FM_PCH_PLD_DATA
  GND(2)  = GND
  PT9A  = FM_ADR_SMI_GPIO_R_N
  PT10B  = FM_CPU1_THERMTRIP_LATCH_LVT3_N
  PT12C_TDO  = JTAG_PLD_TDO
  PT13B  = FM_BMC_ONCTL_N
  PT17A_PCLKT0_1  = FM_ADR_COMPLETE
  PT18D_SDA_PCLKC0_0  = SMB_SENSOR_STBY_LVC3_SDA
  PT20C_JTAGENB  = FM_JTAG_PLD_EN_DEBUG
  PT21B  = FM_CPU0_CD_PRES
  PT23A  = FM_SLPS4_N
  PT24D_DONE  = TP_CPLD1_PT24D_DONE
  GND(3)  = GND
  PR1C  = FM_DB1200_PWRGD
  PR2C  = PWRGD_PCH_PWROK
  PL1B_L_GPLLC_FB  = TP_CPLD1_PL1B_L_GPLLC_FB
  PL2D  = FM_MEM_EVENT_FUNC
  PL1A_L_GPLLT_FB  = TP_CPLD1_PL1A_L_GPLLT_FB
  GND(4)  = GND
  VCCIO0(3)  = P3V3_STBY
  PT12A  = RST_PCIE_CPU_DEV0_N
  PT13D  = FM_FORCE_ADR_N
  PT17C  = TP_CPLD1_PT17C
  PT18B  = RST_PCIE_MIDPLANE_N
  PT20A  = TP_CPLD1_PT20A
  PT21D  = FM_CPU0_AND_CPU1_MCP_PRES
  VCCIO0(1)  = P3V3_STBY
  GND(5)  = GND
  PR1A  = PWRGD_SYS_PWROK
  PR2D  = PWRGD_P1V8MCP_CPU0
  PR2A  = PWRGD_P1V8MCP_CPU1
  PL3A_PCLKT5_0  = CLK_32K_SUSCLK_PLD
  PL2A_L_GPLLT_IN  = FM_CPU_CATERR_DLY_LVT3_N
  PL2B_L_GPLLC_IN  = TP_CPLD1_PL2B_L_GPLLC_IN
  VCCIO5(0)  = P3V3_STBY
  GND(6)  = GND
  PT13C  = FM_CPU1_FIVR_FAULT_LVT3_N
  PT12B  = PWRGD_P1V15_BMC_STBY
  PT16B  = TP_CPLD1_PT16B
  PT17D  = FM_SLP_SUS_N
  PT20B  = TP_CPLD1_PT20B
  PT19D  = TP_CPLD1_PT19D
  GND(7)  = GND
  VCCIO1(0)  = P3V3_STBY
  PR2B  = FM_CPLD_ADR_TRIGGER_N
  PR1B  = RST_PLTRST_N
  PR3A  = FM_P1V8MCP_CPU0_EN
  PL4B  = FM_CPU0_PROC_ID0
  PL3B_PCLKC5_0  = FM_CPU0_PKGID0
  PL4A  = FM_CPU0_PROC_ID1
  PL3C  = PU_RST_PERST_BIT0
  PL5C  = FM_CPU0_FIVR_FAULT_LVT3_N
  GND(8)  = GND
  PT16A  = FM_PLD_DEBUG_MODE_N
  PT18A  = SGPIO_BMC_DIN_R
  PT19C  = FM_PS_EN
  PT21C  = FM_CPU1_CD_PRES_N
  GND(9)  = GND
  PR4C  = FM_P1V8MCP_CPU1_EN
  PR3C  = PWRGD_CPUPWRGD
  PR4A  = RST_BMC_SYSRST_BTN_OUT_B_R1_N
  PR3B  = FM_CPU0_MCP_CLK_EN_N
  PR4B  = FM_CPU1_MCP_CLK_EN_N
  PL6A  = FM_SLPS3_N
  PL5A  = FM_CPU0_PKGID2
  PL5B  = FM_CPU0_PKGID1
  PL4D  = RST_RSMRST_R_N
  PL4C  = FM_DEBUG_RST_BTN_N
  PL3D  = FM_PWR_BTN_R2_N
  VCC(4)  = P3V3_STBY
  VCCIO0(0)  = P3V3_STBY
  VCCIO0(2)  = P3V3_STBY
  VCC(5)  = P3V3_STBY
  PR5C  = FM_WBG_PRSNT_N
  PR3D  = FM_CPU0_THERMTRIP_LATCH_LVT3_N
  PR4D  = FM_CPU1_FIVR_FAULT_LVT3
  PR5B  = FM_CPU1_THERMTRIP_LVT3_N
  PR5A  = FM_UV_ADR_TRIGGER_N
  PR6A  = FM_FAST_PROCHOT_THROTTLE_IN_N
  PL7B  = RST_PCIE_CPU_DEV3_N
  PL6B  = FM_PVCCMCP_CPU0_EN
  PL7A  = RST_PCIE_CPU_DEV2_N
  PL6C  = FM_MP_PS_FAIL_N
  PL9C  = NC
  PL5D  = PWRGD_P3V3
  VCCIO4(1)  = P3V3_STBY
  GND(10)  = GND
  GND(11)  = GND
  VCCIO1(1)  = P3V3_STBY
  PR9C  = TP_CPLD1_PR9C
  PR5D  = FM_UV_ADR_TRIGGER_EN
  PR6C  = FM_PVDDQ_GHJ_EN
  PR7A_PCLKT1_0  = TP_CPLD1_PR7A_PCLKT1_0
  PR6B  = FM_PVDDQ_KLM_EN
  PR7B_PCLKC1_0  = TP_CPLD1_PR7B_PCLKC1_0
  PL7C_PCLKT4_0  = SGPIO_BMC_CLK
  PL9A  = SGPIO_BMC_DOUT
  PL7D_PCLKC4_0  = TP_CPLD1_PL7D_PCLKT4_0
  PL9D  = NC
  PL10C  = UART_BMC_RXD5
  PL6D  = PWRGD_P5V
  VCCIO4(0)  = P3V3_STBY
  GND(12)  = GND
  GND(13)  = GND
  VCCIO1(2)  = P3V3_STBY
  PR10C  = TP_CPLD1_PR10C
  PR6D  = FM_FAST_PROCHOT_THROTTLE_DLY_N
  PR9D  = TP_CPLD1_PR9D
  PR7D  = TP_CPLD1_PR7D
  PR9A  = TP_CPLD1_PR9A
  PR7C  = TP_CPLD1_PR7C
  PL9B  = FM_PVCCIOMCP_CPU0_EN
  PL10B  = SP1_BMC_HOST_UART_TX
  PL10A  = SP1_BMC_HOST_UART_RX
  PL11C  = SGPIO_BMC_LD_N
  PL12C  = PWRGD_PVCCIN_CPU0
  PL10D  = UART_BMC_TXD5
  VCC(6)  = P3V3_STBY
  VCCIO2(2)  = P3V3_STBY
  VCCIO2(0)  = P3V3_STBY
  VCC(7)  = P3V3_STBY
  PR12C  = RST_PLTRST_BUF_N
  PR11D  = FM_MEM_THERM_EVENT_PCH_N
  PR11C  = FM_MEM_THERM_EVENT_LVT3_N
  PR10A  = FM_PVDDQ_ABC_EN
  PR10B  = FM_PVDDQ_DEF_EN
  PR9B  = PU_FAB2_MARKER_CPLD
  PL11A  = PWRGD_PVSA_CPU0
  PL12A_PCLKT3_0  = CLK_25M_CPLD
  PL11B  = TP_CPLD1_PL11A
  PL12D  = PWRGD_PVCCMCP_CPU1
  PL11D  = PWRGD_CPU0_LVC3
  GND(14)  = GND
  PB8D  = FM_OC0_USB_N
  PB11D  = PWRGD_PVCCIO_CPU0
  PB12D  = FM_IE_DISABLE_N
  PB18D  = FM_SOL_UART_CH_SEL
  GND(15)  = GND
  PR10D  = PWRGD_P3V3_STBY
  PR12D  = TP_CPLD1_PR12D
  PR11B  = TP_CPLD1_PR11B
  PR12A  = FM_THERMTRIP_DLY
  PR11A  = PWRGD_PVCCIO_CPU1
  PL12B_PCLKC3_0  = RST_RSMRST_DLY
  PL14A  = PWRGD_PVPP_GHJ
  PL13A  = RST_PCIE_RISER1_PERST_N
  VCCIO3(0)  = P3V3_STBY
  GND(16)  = GND
  PB11C  = PWRGD_PVPP_DEF
  PB9C  = FM_PVCCIO_CPU0_EN
  PB16C  = FM_PVCCMCP_CPU1_EN
  PB18C  = FM_CPLD_UART_CH_LOCK_N
  PB21C  = PWRGD_CPU1_LVC3
  PB19D  = XDP_PWRGD_RST_N
  GND(17)  = GND
  VCCIO1(3)  = P3V3_STBY
  PR13A  = FM_CPU1_PROC_ID1
  PR13B  = FM_CPU1_PROC_ID0
  PR12B  = FM_CPU0_FIVR_FAULT_LVT3
  PL13B  = PWRGD_PVCCIN_CPU1
  PL13C  = PWRGD_PVPP_KLM
  PL14B  = RST_CD_CPU0_POR_N
  GND(18)  = GND
  VCCIO2(3)  = P3V3_STBY
  PB8C  = PWRGD_PVCCIOMCP_CPU0
  PB9D  = PWRGD_PVPP_ABC
  PB12C  = FM_156M_CPU1_BRD_OSC_EN
  PB16D  = FM_CPLD_BMC_PWRDN_N
  PB19C  = RST_CPU1_LVC3_R1_N
  PB21D  = XDP_SYSPWROK
  VCCIO2(1)  = P3V3_STBY
  GND(19)  = GND
  PR14B  = FM_CPU1_VRM_OSC_EN
  PR13C  = FM_CPU0_THERMTRIP_LVT3_N
  PR14A  = FM_PVCCIN_PVCCSA_CPU1_EN_LVC1
  PL13D  = FM_GLOBAL_RST_WARN_N
  PL14D  = FM_UART_ALERT_N
  GND(20)  = GND
  PB3A  = FM_CPU1_RC_EN
  PB5B  = PWRGD_PVCCMCP_CPU0
  PB8A_MCLK_CCLK  = TP_CPLD1_PB8A_MCLK_CCLK
  PB9B  = FM_PVCCIOMCP_CPU1_EN
  PB12A  = PWRGD_PVNN_P1V05_PCH
  PB16B_PCLKC2_1  = TP_CPLD1_PB16B_PCLKC2_1
  PB19A  = RST_CD_CPU1_POR_N
  PB21B  = FM_UARTSW_MSB_N
  PB24A  = FM_CPU1_PKGID1
  PB25B_SI_SISPI  = TP_CPLD1_PB25B_SI_SISPI
  GND(21)  = GND
  PR14C  = FM_PVPP_CPU0_EN
  PR13D  = FM_PVPP_CPU1_EN
  PL14C  = FM_BMC_CPLD_GPO
  GND(22)  = GND
  PB3D  = FM_CPU0_RC_EN
  PB6D  = FM_BMC_CPLD_MP_RST_N
  PB5A_CSSPIN  = TP_CPLD1_PB5A_CSSPIN
  PB6B  = RST_PCIE_M2_DEV_N
  PB9A  = PWRGD_PVTT_CPU1
  PB11B_PCLKC2_0  = FM_CPLD_USB_P0_EN_N
  PB18A  = FM_UARTSW_LSB_N
  PB19B  = RST_CPU0_LVC3_R1_N
  PB22A  = FM_DB1200ZL_BCLKS_EN_N
  PB25A_SN  = FM_CPU1_PKGID0
  PB22C  = FM_CPU0_VRM_OSC_EN
  PB25D  = FM_CPU_CATERR_LVT3_N
  GND(23)  = GND
  PR14D  = FM_P12V_MAIN_SW_EN
  VCC(2)  = P3V3_STBY
  PB3C  = FM_ADR_MODE_SEL
  PB6C  = FM_DIS_ADR_DLY
  PB3B  = PWRGD_PVSA_CPU1
  PB6A  = PWRGD_PVCCIOMCP_CPU1
  PB8B_SO_SPISO  = TP_CPLD1_PB8B_SO_SPISO
  PB11A_PCLKT2_0  = FM_PVCCIO_CPU1_EN
  PB12B  = FM_CPLD_DBG_PWR_EN_N
  PB16A_PCLKT2_1  = TP_CPLD1_PB16A_PCLKT2_1
  PB18B  = FM_156M_CPU0_BRD_OSC_EN
  PB21A  = FM_CPU1_PKGID2
  PB22B  = FM_CPU1_SKTOCC_LVT3_N
  PB24B  = FM_CPU_MSMI_LVT3_N
  PB22D  = FM_CPU0_SKTOCC_LVT3_N
  PB25C  = PWRGD_DRAMPWRGD
  VCC(3)  = P3V3_STBY

(kicad_pcb
	(version 20260206)
	(generator "pcbnew")
	(generator_version "10.0")
	(general
		(thickness 1.6)
		(legacy_teardrops no)
	)
	(paper "A4")
	(title_block
		(title "Wiwynn_Tioga_Pass_MB.brd")
		(comment 1 "Tioga Pass / footprint 2035 of 4770 (U8D7), pads 181-225 of 256")
	)
	(layers
		(0 "F.Cu" signal "TOP")
		(4 "In1.Cu" signal "L2GND")
		(6 "In2.Cu" signal "L3")
		(8 "In3.Cu" signal "L4GND")
		(10 "In4.Cu" signal "L5")
		(12 "In5.Cu" signal "L6GND")
		(14 "In6.Cu" signal "L7VCC")
		(16 "In7.Cu" signal "L8VCC")
		(18 "In8.Cu" signal "L9GND")
		(20 "In9.Cu" signal "L10")
		(22 "In10.Cu" signal "L11GND")
		(24 "In11.Cu" signal "L12")
		(26 "In12.Cu" signal "L13GND")
		(2 "B.Cu" signal "BOTTOM")
		(9 "F.Adhes" user "F.Adhesive")
		(11 "B.Adhes" user "B.Adhesive")
		(13 "F.Paste" user "Package Geometry/Pastemask Top")
		(15 "B.Paste" user "Package Geometry/Pastemask Bottom")
		(5 "F.SilkS" user "Ref Des/Silkscreen Top")
		(7 "B.SilkS" user "Ref Des/Silkscreen Bottom")
		(1 "F.Mask" user "Board Geometry/Soldermask Top")
		(3 "B.Mask" user "Board Geometry/Soldermask Bottom")
		(17 "Dwgs.User" user "User.Drawings")
		(19 "Cmts.User" user "User.Comments")
		(21 "Eco1.User" user "User.Eco1")
		(23 "Eco2.User" user "User.Eco2")
		(25 "Edge.Cuts" user "Board Geometry/Outline")
		(27 "Margin" user)
		(31 "F.CrtYd" user "Package Geometry/Place Bound Top")
		(29 "B.CrtYd" user "Package Geometry/Place Bound Bottom")
		(35 "F.Fab" user "Ref Des/Assembly Top")
		(33 "B.Fab" user "Ref Des/Assembly Bottom")
	)
	(footprint ""
		(layer "F.Cu")
		(at 372.745 -74.295 180)
		(property "Reference" "U8D7"
			(at -0.635 -8.28167 0)
			(unlocked yes)
			(layer "F.SilkS")
			(effects
				(font
					(size 0.7874 0.5842)
					(thickness 0.1524)
				)
			)
		)
		(property "Value" ""
			(at 0 0 180)
			(layer "F.Fab")
			(effects
				(font
					(size 1.27 1.27)
				)
			)
		)
		(duplicate_pad_numbers_are_jumpers no)
		(pad "M5" smd circle
			(at -2.800096 2.800096 180)
			(size 0.3556 0.3556)
			(layers "F.Cu" "F.Mask" "F.Paste")
			(net "GND")
		)
		(pad "M6" smd circle
			(at -1.999996 2.800096 180)
			(size 0.3556 0.3556)
			(layers "F.Cu" "F.Mask" "F.Paste")
			(net "PWRGD_PVPP_DEF")
		)
		(pad "M7" smd circle
			(at -1.199896 2.800096 180)
			(size 0.3556 0.3556)
			(layers "F.Cu" "F.Mask" "F.Paste")
			(net "FM_PVCCIO_CPU0_EN")
		)
		(pad "M8" smd circle
			(at -0.40005 2.800096 180)
			(size 0.3556 0.3556)
			(layers "F.Cu" "F.Mask" "F.Paste")
			(net "FM_PVCCMCP_CPU1_EN")
		)
		(pad "M9" smd circle
			(at 0.40005 2.800096 180)
			(size 0.3556 0.3556)
			(layers "F.Cu" "F.Mask" "F.Paste")
			(net "FM_CPLD_UART_CH_LOCK_N")
		)
		(pad "M10" smd circle
			(at 1.199896 2.800096 180)
			(size 0.3556 0.3556)
			(layers "F.Cu" "F.Mask" "F.Paste")
			(net "PWRGD_CPU1_LVC3")
		)
		(pad "M11" smd circle
			(at 1.999996 2.800096 180)
			(size 0.3556 0.3556)
			(layers "F.Cu" "F.Mask" "F.Paste")
			(net "XDP_PWRGD_RST_N")
		)
		(pad "M12" smd circle
			(at 2.800096 2.800096 180)
			(size 0.3556 0.3556)
			(layers "F.Cu" "F.Mask" "F.Paste")
			(net "GND")
		)
		(pad "M13" smd circle
			(at 3.599942 2.800096 180)
			(size 0.3556 0.3556)
			(layers "F.Cu" "F.Mask" "F.Paste")
			(net "P3V3_STBY")
		)
		(pad "M14" smd circle
			(at 4.400042 2.800096 180)
			(size 0.3556 0.3556)
			(layers "F.Cu" "F.Mask" "F.Paste")
			(net "FM_CPU1_PROC_ID1")
		)
		(pad "M15" smd circle
			(at 5.199888 2.800096 180)
			(size 0.3556 0.3556)
			(layers "F.Cu" "F.Mask" "F.Paste")
			(net "FM_CPU1_PROC_ID0")
		)
		(pad "M16" smd circle
			(at 5.999988 2.800096 180)
			(size 0.3556 0.3556)
			(layers "F.Cu" "F.Mask" "F.Paste")
			(net "FM_CPU0_FIVR_FAULT_LVT3")
		)
		(pad "N1" smd circle
			(at -5.999988 3.599942 180)
			(size 0.3556 0.3556)
			(layers "F.Cu" "F.Mask" "F.Paste")
			(net "PWRGD_PVCCIN_CPU1")
		)
		(pad "N2" smd circle
			(at -5.199888 3.599942 180)
			(size 0.3556 0.3556)
			(layers "F.Cu" "F.Mask" "F.Paste")
			(net "PWRGD_PVPP_KLM")
		)
		(pad "N3" smd circle
			(at -4.400042 3.599942 180)
			(size 0.3556 0.3556)
			(layers "F.Cu" "F.Mask" "F.Paste")
			(net "RST_CD_CPU0_POR_N")
		)
		(pad "N4" smd circle
			(at -3.599942 3.599942 180)
			(size 0.3556 0.3556)
			(layers "F.Cu" "F.Mask" "F.Paste")
			(net "GND")
		)
		(pad "N5" smd circle
			(at -2.800096 3.599942 180)
			(size 0.3556 0.3556)
			(layers "F.Cu" "F.Mask" "F.Paste")
			(net "P3V3_STBY")
		)
		(pad "N6" smd circle
			(at -1.999996 3.599942 180)
			(size 0.3556 0.3556)
			(layers "F.Cu" "F.Mask" "F.Paste")
			(net "PWRGD_PVCCIOMCP_CPU0")
		)
		(pad "N7" smd circle
			(at -1.199896 3.599942 180)
			(size 0.3556 0.3556)
			(layers "F.Cu" "F.Mask" "F.Paste")
			(net "PWRGD_PVPP_ABC")
		)
		(pad "N8" smd circle
			(at -0.40005 3.599942 180)
			(size 0.3556 0.3556)
			(layers "F.Cu" "F.Mask" "F.Paste")
			(net "FM_156M_CPU1_BRD_OSC_EN")
		)
		(pad "N9" smd circle
			(at 0.40005 3.599942 180)
			(size 0.3556 0.3556)
			(layers "F.Cu" "F.Mask" "F.Paste")
			(net "FM_CPLD_BMC_PWRDN_N")
		)
		(pad "N10" smd circle
			(at 1.199896 3.599942 180)
			(size 0.3556 0.3556)
			(layers "F.Cu" "F.Mask" "F.Paste")
			(net "RST_CPU1_LVC3_R1_N")
		)
		(pad "N11" smd circle
			(at 1.999996 3.599942 180)
			(size 0.3556 0.3556)
			(layers "F.Cu" "F.Mask" "F.Paste")
			(net "XDP_SYSPWROK")
		)
		(pad "N12" smd circle
			(at 2.800096 3.599942 180)
			(size 0.3556 0.3556)
			(layers "F.Cu" "F.Mask" "F.Paste")
			(net "P3V3_STBY")
		)
		(pad "N13" smd circle
			(at 3.599942 3.599942 180)
			(size 0.3556 0.3556)
			(layers "F.Cu" "F.Mask" "F.Paste")
			(net "GND")
		)
		(pad "N14" smd circle
			(at 4.400042 3.599942 180)
			(size 0.3556 0.3556)
			(layers "F.Cu" "F.Mask" "F.Paste")
			(net "FM_CPU1_VRM_OSC_EN")
		)
		(pad "N15" smd circle
			(at 5.199888 3.599942 180)
			(size 0.3556 0.3556)
			(layers "F.Cu" "F.Mask" "F.Paste")
			(net "FM_CPU0_THERMTRIP_LVT3_N")
		)
		(pad "N16" smd circle
			(at 5.999988 3.599942 180)
			(size 0.3556 0.3556)
			(layers "F.Cu" "F.Mask" "F.Paste")
			(net "FM_PVCCIN_PVCCSA_CPU1_EN_LVC1")
		)
		(pad "P1" smd circle
			(at -5.999988 4.400042 180)
			(size 0.3556 0.3556)
			(layers "F.Cu" "F.Mask" "F.Paste")
			(net "FM_GLOBAL_RST_WARN_N")
		)
		(pad "P2" smd circle
			(at -5.199888 4.400042 180)
			(size 0.3556 0.3556)
			(layers "F.Cu" "F.Mask" "F.Paste")
			(net "FM_UART_ALERT_N")
		)
		(pad "P3" smd circle
			(at -4.400042 4.400042 180)
			(size 0.3556 0.3556)
			(layers "F.Cu" "F.Mask" "F.Paste")
			(net "GND")
		)
		(pad "P4" smd circle
			(at -3.599942 4.400042 180)
			(size 0.3556 0.3556)
			(layers "F.Cu" "F.Mask" "F.Paste")
			(net "FM_CPU1_RC_EN")
		)
		(pad "P5" smd circle
			(at -2.800096 4.400042 180)
			(size 0.3556 0.3556)
			(layers "F.Cu" "F.Mask" "F.Paste")
			(net "PWRGD_PVCCMCP_CPU0")
		)
		(pad "P6" smd circle
			(at -1.999996 4.400042 180)
			(size 0.3556 0.3556)
			(layers "F.Cu" "F.Mask" "F.Paste")
			(net "TP_CPLD1_PB8A_MCLK_CCLK")
		)
		(pad "P7" smd circle
			(at -1.199896 4.400042 180)
			(size 0.3556 0.3556)
			(layers "F.Cu" "F.Mask" "F.Paste")
			(net "FM_PVCCIOMCP_CPU1_EN")
		)
		(pad "P8" smd circle
			(at -0.40005 4.400042 180)
			(size 0.3556 0.3556)
			(layers "F.Cu" "F.Mask" "F.Paste")
			(net "PWRGD_PVNN_P1V05_PCH")
		)
		(pad "P9" smd circle
			(at 0.40005 4.400042 180)
			(size 0.3556 0.3556)
			(layers "F.Cu" "F.Mask" "F.Paste")
			(net "TP_CPLD1_PB16B_PCLKC2_1")
		)
		(pad "P10" smd circle
			(at 1.199896 4.400042 180)
			(size 0.3556 0.3556)
			(layers "F.Cu" "F.Mask" "F.Paste")
			(net "RST_CD_CPU1_POR_N")
		)
		(pad "P11" smd circle
			(at 1.999996 4.400042 180)
			(size 0.3556 0.3556)
			(layers "F.Cu" "F.Mask" "F.Paste")
			(net "FM_UARTSW_MSB_N")
		)
		(pad "P12" smd circle
			(at 2.800096 4.400042 180)
			(size 0.3556 0.3556)
			(layers "F.Cu" "F.Mask" "F.Paste")
			(net "FM_CPU1_PKGID1")
		)
		(pad "P13" smd circle
			(at 3.599942 4.400042 180)
			(size 0.3556 0.3556)
			(layers "F.Cu" "F.Mask" "F.Paste")
			(net "TP_CPLD1_PB25B_SI_SISPI")
		)
		(pad "P14" smd circle
			(at 4.400042 4.400042 180)
			(size 0.3556 0.3556)
			(layers "F.Cu" "F.Mask" "F.Paste")
			(net "GND")
		)
		(pad "P15" smd circle
			(at 5.199888 4.400042 180)
			(size 0.3556 0.3556)
			(layers "F.Cu" "F.Mask" "F.Paste")
			(net "FM_PVPP_CPU0_EN")
		)
		(pad "P16" smd circle
			(at 5.999988 4.400042 180)
			(size 0.3556 0.3556)
			(layers "F.Cu" "F.Mask" "F.Paste")
			(net "FM_PVPP_CPU1_EN")
		)
		(pad "R1" smd circle
			(at -5.999988 5.199888 180)
			(size 0.3556 0.3556)
			(layers "F.Cu" "F.Mask" "F.Paste")
			(net "FM_BMC_CPLD_GPO")
		)
	)
)
